# T6G (Grand Teton) — schematic netlist excerpt (pin names and nets, part order shuffled) for the footprints in the layout excerpt that follows; sources: Cadence DE-HDL packaged netlist, KiCad conversion of 04192023_DAF0TMB3IC0_F0TG_MB_C_brd_V02_OCP.brd

R1454  Q_RES  4.7K 5% EMPTY  pkg 0201LF  page 331 : A = P1V8_CPU1_RT_1D ; B = JTAG_TDI_RT_CPU1_P1
R3998  Q_RES  0 5% CHIP  pkg 0402LF  page 152 : A = P12V_SCM_EN ; B = P12V_SCM_EN_R2
R252  Q_RES  0 5% CHIP  pkg 0402LF  page 81 : A = FM_CPU1_PWR_GD_IN ; B = CPU1_PWR_GD_IN

(kicad_pcb
	(version 20260206)
	(generator "pcbnew")
	(generator_version "10.0")
	(general
		(thickness 1.6)
		(legacy_teardrops no)
	)
	(paper "A4")
	(title_block
		(title "04192023_DAF0TMB3IC0_F0TG_MB_C_brd_V02_OCP.brd")
		(comment 1 "Grand Teton / footprints 4742-4744 of 8354")
	)
	(layers
		(0 "F.Cu" signal "TOP")
		(4 "In1.Cu" signal "GND")
		(6 "In2.Cu" signal "IN1")
		(8 "In3.Cu" signal "GND1")
		(10 "In4.Cu" signal "IN2")
		(12 "In5.Cu" signal "GND2")
		(14 "In6.Cu" signal "IN3")
		(16 "In7.Cu" signal "GND3")
		(18 "In8.Cu" signal "VCC")
		(20 "In9.Cu" signal "VCC1")
		(22 "In10.Cu" signal "GND4")
		(24 "In11.Cu" signal "IN4")
		(26 "In12.Cu" signal "GND5")
		(28 "In13.Cu" signal "IN5")
		(30 "In14.Cu" signal "GND6")
		(32 "In15.Cu" signal "IN6")
		(34 "In16.Cu" signal "GND7")
		(2 "B.Cu" signal "BOTTOM")
		(9 "F.Adhes" user "F.Adhesive")
		(11 "B.Adhes" user "B.Adhesive")
		(13 "F.Paste" user "Package Geometry/Pastemask Top")
		(15 "B.Paste" user "Package Geometry/Pastemask Bottom")
		(5 "F.SilkS" user "Ref Des/Silkscreen Top")
		(7 "B.SilkS" user "Ref Des/Silkscreen Bottom")
		(1 "F.Mask" user "Board Geometry/Soldermask Top")
		(3 "B.Mask" user "Board Geometry/Soldermask Bottom")
		(17 "Dwgs.User" user "User.Drawings")
		(19 "Cmts.User" user "User.Comments")
		(21 "Eco1.User" user "User.Eco1")
		(23 "Eco2.User" user "User.Eco2")
		(25 "Edge.Cuts" user "Board Geometry/Outline")
		(27 "Margin" user)
		(31 "F.CrtYd" user "Package Geometry/Place Bound Top")
		(29 "B.CrtYd" user "Package Geometry/Place Bound Bottom")
		(35 "F.Fab" user "Ref Des/Assembly Top")
		(33 "B.Fab" user "Ref Des/Assembly Bottom")
	)
	(footprint ""
		(layer "F.Cu")
		(at 180.074062 -32.935672 -90)
		(property "Reference" "R3998"
			(at 0 0 270)
			(layer "F.SilkS")
			(hide yes)
			(effects
				(font
					(size 1.27 1.27)
				)
			)
		)
		(property "Value" ""
			(at 0 0 270)
			(layer "F.Fab")
			(effects
				(font
					(size 1.27 1.27)
				)
			)
		)
		(duplicate_pad_numbers_are_jumpers no)
		(fp_line
			(start -0.7874 0.4064)
			(end -0.7874 -0.4064)
			(stroke
				(width 0.1524)
				(type default)
			)
			(layer "F.SilkS")
		)
		(fp_line
			(start 0.7874 0.4064)
			(end -0.7874 0.4064)
			(stroke
				(width 0.1524)
				(type default)
			)
			(layer "F.SilkS")
		)
		(fp_line
			(start -0.7874 -0.4064)
			(end 0.7874 -0.4064)
			(stroke
				(width 0.1524)
				(type default)
			)
			(layer "F.SilkS")
		)
		(fp_line
			(start 0.7874 -0.4064)
			(end 0.7874 0.4064)
			(stroke
				(width 0.1524)
				(type default)
			)
			(layer "F.SilkS")
		)
		(fp_line
			(start -0.67945 0.3048)
			(end -0.67945 -0.305054)
			(stroke
				(width 0.1)
				(type default)
			)
			(layer "F.Fab")
		)
		(fp_line
			(start -0.12065 0.3048)
			(end -0.67945 0.3048)
			(stroke
				(width 0.1)
				(type default)
			)
			(layer "F.Fab")
		)
		(fp_line
			(start 0.120396 0.3048)
			(end 0.120396 0.2794)
			(stroke
				(width 0.1)
				(type default)
			)
			(layer "F.Fab")
		)
		(fp_line
			(start 0.67945 0.3048)
			(end 0.120396 0.3048)
			(stroke
				(width 0.1)
				(type default)
			)
			(layer "F.Fab")
		)
		(fp_line
			(start -0.12065 0.2794)
			(end -0.12065 0.3048)
			(stroke
				(width 0.1)
				(type default)
			)
			(layer "F.Fab")
		)
		(fp_line
			(start 0.120396 0.2794)
			(end -0.12065 0.2794)
			(stroke
				(width 0.1)
				(type default)
			)
			(layer "F.Fab")
		)
		(fp_line
			(start -0.12065 -0.2794)
			(end 0.12065 -0.2794)
			(stroke
				(width 0.1)
				(type default)
			)
			(layer "F.Fab")
		)
		(fp_line
			(start 0.12065 -0.2794)
			(end 0.12065 -0.3048)
			(stroke
				(width 0.1)
				(type default)
			)
			(layer "F.Fab")
		)
		(fp_line
			(start 0.12065 -0.3048)
			(end 0.67945 -0.3048)
			(stroke
				(width 0.1)
				(type default)
			)
			(layer "F.Fab")
		)
		(fp_line
			(start 0.67945 -0.3048)
			(end 0.67945 0.3048)
			(stroke
				(width 0.1)
				(type default)
			)
			(layer "F.Fab")
		)
		(fp_line
			(start -0.67945 -0.305054)
			(end -0.12065 -0.305054)
			(stroke
				(width 0.1)
				(type default)
			)
			(layer "F.Fab")
		)
		(fp_line
			(start -0.12065 -0.305054)
			(end -0.12065 -0.2794)
			(stroke
				(width 0.1)
				(type default)
			)
			(layer "F.Fab")
		)
		(pad "1" smd circle
			(at -0.40005 0 270)
			(size 0 0)
			(layers "F.Cu" "F.Mask" "F.Paste")
			(net "P12V_SCM_EN")
		)
		(pad "2" smd circle
			(at 0.40005 0 270)
			(size 0 0)
			(layers "F.Cu" "F.Mask" "F.Paste")
			(net "P12V_SCM_EN_R2")
		)
	)
	(footprint ""
		(layer "F.Cu")
		(at 96.0628 -417.2204 180)
		(property "Reference" "R1454"
			(at 0 0 180)
			(layer "F.SilkS")
			(hide yes)
			(effects
				(font
					(size 1.27 1.27)
				)
			)
		)
		(property "Value" ""
			(at 0 0 180)
			(layer "F.Fab")
			(effects
				(font
					(size 1.27 1.27)
				)
			)
		)
		(duplicate_pad_numbers_are_jumpers no)
		(fp_line
			(start 0.32512 0.175006)
			(end -0.32512 0.175006)
			(stroke
				(width 0.1)
				(type default)
			)
			(layer "F.Fab")
		)
		(fp_line
			(start 0.32512 -0.175006)
			(end 0.32512 0.175006)
			(stroke
				(width 0.1)
				(type default)
			)
			(layer "F.Fab")
		)
		(fp_line
			(start -0.32512 0.175006)
			(end -0.32512 -0.175006)
			(stroke
				(width 0.1)
				(type default)
			)
			(layer "F.Fab")
		)
		(fp_line
			(start -0.32512 -0.175006)
			(end 0.32512 -0.175006)
			(stroke
				(width 0.1)
				(type default)
			)
			(layer "F.Fab")
		)
		(pad "1" smd rect
			(at -0.2667 0 180)
			(size 0.3048 0.381)
			(layers "F.Cu" "F.Mask" "F.Paste")
			(net "P1V8_CPU1_RT_1D")
		)
		(pad "2" smd rect
			(at 0.2667 0)
			(size 0.3048 0.381)
			(layers "F.Cu" "F.Mask" "F.Paste")
			(net "JTAG_TDI_RT_CPU1_P1")
		)
	)
	(footprint ""
		(layer "F.Cu")
		(at 194.31 -137.632948 90)
		(property "Reference" "R252"
			(at 0 0 90)
			(layer "F.SilkS")
			(hide yes)
			(effects
				(font
					(size 1.27 1.27)
				)
			)
		)
		(property "Value" ""
			(at 0 0 90)
			(layer "F.Fab")
			(effects
				(font
					(size 1.27 1.27)
				)
			)
		)
		(duplicate_pad_numbers_are_jumpers no)
		(fp_line
			(start 0.7874 -0.4064)
			(end 0.7874 0.4064)
			(stroke
				(width 0.1524)
				(type default)
			)
			(layer "F.SilkS")
		)
		(fp_line
			(start -0.7874 -0.4064)
			(end 0.7874 -0.4064)
			(stroke
				(width 0.1524)
				(type default)
			)
			(layer "F.SilkS")
		)
		(fp_line
			(start 0.7874 0.4064)
			(end -0.7874 0.4064)
			(stroke
				(width 0.1524)
				(type default)
			)
			(layer "F.SilkS")
		)
		(fp_line
			(start -0.7874 0.4064)
			(end -0.7874 -0.4064)
			(stroke
				(width 0.1524)
				(type default)
			)
			(layer "F.SilkS")
		)
		(fp_line
			(start -0.12065 -0.305054)
			(end -0.12065 -0.2794)
			(stroke
				(width 0.1)
				(type default)
			)
			(layer "F.Fab")
		)
		(fp_line
			(start -0.67945 -0.305054)
			(end -0.12065 -0.305054)
			(stroke
				(width 0.1)
				(type default)
			)
			(layer "F.Fab")
		)
		(fp_line
			(start 0.67945 -0.3048)
			(end 0.67945 0.3048)
			(stroke
				(width 0.1)
				(type default)
			)
			(layer "F.Fab")
		)
		(fp_line
			(start 0.12065 -0.3048)
			(end 0.67945 -0.3048)
			(stroke
				(width 0.1)
				(type default)
			)
			(layer "F.Fab")
		)
		(fp_line
			(start 0.12065 -0.2794)
			(end 0.12065 -0.3048)
			(stroke
				(width 0.1)
				(type default)
			)
			(layer "F.Fab")
		)
		(fp_line
			(start -0.12065 -0.2794)
			(end 0.12065 -0.2794)
			(stroke
				(width 0.1)
				(type default)
			)
			(layer "F.Fab")
		)
		(fp_line
			(start 0.120396 0.2794)
			(end -0.12065 0.2794)
			(stroke
				(width 0.1)
				(type default)
			)
			(layer "F.Fab")
		)
		(fp_line
			(start -0.12065 0.2794)
			(end -0.12065 0.3048)
			(stroke
				(width 0.1)
				(type default)
			)
			(layer "F.Fab")
		)
		(fp_line
			(start 0.67945 0.3048)
			(end 0.120396 0.3048)
			(stroke
				(width 0.1)
				(type default)
			)
			(layer "F.Fab")
		)
		(fp_line
			(start 0.120396 0.3048)
			(end 0.120396 0.2794)
			(stroke
				(width 0.1)
				(type default)
			)
			(layer "F.Fab")
		)
		(fp_line
			(start -0.12065 0.3048)
			(end -0.67945 0.3048)
			(stroke
				(width 0.1)
				(type default)
			)
			(layer "F.Fab")
		)
		(fp_line
			(start -0.67945 0.3048)
			(end -0.67945 -0.305054)
			(stroke
				(width 0.1)
				(type default)
			)
			(layer "F.Fab")
		)
		(pad "1" smd circle
			(at -0.40005 0 90)
			(size 0 0)
			(layers "F.Cu" "F.Mask" "F.Paste")
			(net "FM_CPU1_PWR_GD_IN")
		)
		(pad "2" smd circle
			(at 0.40005 0 90)
			(size 0 0)
			(layers "F.Cu" "F.Mask" "F.Paste")
			(net "CPU1_PWR_GD_IN")
		)
	)
)
